(kicad_pcb
	(version 20260206)
	(generator "pcbnew")
	(generator_version "10.0")
	(general
		(thickness 1.6)
		(legacy_teardrops no)
	)
	(paper "A4")
	(title_block
		(title "Bryce Canyon_F.DPB_16315-1-OCP.brd")
		(comment 1 "Bryce Canyon / footprints 1503-1509 of 2223")
	)
	(layers
		(0 "F.Cu" signal "TOP")
		(4 "In1.Cu" signal "L2GND")
		(6 "In2.Cu" signal "L3")
		(8 "In3.Cu" signal "L4GND")
		(10 "In4.Cu" signal "L5")
		(12 "In5.Cu" signal "L6VCC")
		(14 "In6.Cu" signal "L7VCC")
		(16 "In7.Cu" signal "L8")
		(18 "In8.Cu" signal "L9GND")
		(20 "In9.Cu" signal "L10")
		(22 "In10.Cu" signal "L11GND")
		(2 "B.Cu" signal "BOTTOM")
		(9 "F.Adhes" user "F.Adhesive")
		(11 "B.Adhes" user "B.Adhesive")
		(13 "F.Paste" user "Package Geometry/Pastemask Top")
		(15 "B.Paste" user "Package Geometry/Pastemask Bottom")
		(5 "F.SilkS" user "Ref Des/Silkscreen Top")
		(7 "B.SilkS" user "Ref Des/Silkscreen Bottom")
		(1 "F.Mask" user "Board Geometry/Soldermask Top")
		(3 "B.Mask" user "Board Geometry/Soldermask Bottom")
		(17 "Dwgs.User" user "User.Drawings")
		(19 "Cmts.User" user "User.Comments")
		(21 "Eco1.User" user "User.Eco1")
		(23 "Eco2.User" user "User.Eco2")
		(25 "Edge.Cuts" user "Board Geometry/Outline")
		(27 "Margin" user)
		(31 "F.CrtYd" user "Package Geometry/Place Bound Top")
		(29 "B.CrtYd" user "Package Geometry/Place Bound Bottom")
		(35 "F.Fab" user "Ref Des/Assembly Top")
		(33 "B.Fab" user "Ref Des/Assembly Bottom")
	)
	(footprint ""
		(layer "F.Cu")
		(at 401.8534 -281.2288 90)
		(property "Reference" "Q50"
			(at 0 0 90)
			(layer "F.SilkS")
			(hide yes)
			(effects
				(font
					(size 1.27 1.27)
				)
			)
		)
		(property "Value" "AO4407AL-GP"
			(at -3.707384 -1.5367 90)
			(unlocked yes)
			(layer "F.Fab")
			(hide yes)
			(effects
				(font
					(size 1.016 1.016)
					(thickness 0.1524)
				)
			)
		)
		(property "Device Type" "SOIC8H69"
			(at -3.707384 -3.0607 90)
			(unlocked yes)
			(layer "F.Fab")
			(hide yes)
			(effects
				(font
					(size 1.016 1.016)
					(thickness 0.1524)
				)
			)
		)
		(duplicate_pad_numbers_are_jumpers no)
		(fp_line
			(start 2.1336 -1.4224)
			(end -2.7432 -1.4224)
			(stroke
				(width 0.1524)
				(type default)
			)
			(layer "F.SilkS")
		)
		(fp_line
			(start -2.7432 -1.4224)
			(end -2.7432 1.4224)
			(stroke
				(width 0.1524)
				(type default)
			)
			(layer "F.SilkS")
		)
		(fp_line
			(start -2.7178 -0.508)
			(end -2.1844 -0.0508)
			(stroke
				(width 0.1524)
				(type default)
			)
			(layer "F.SilkS")
		)
		(fp_line
			(start -2.1844 -0.0508)
			(end -2.7178 0.508)
			(stroke
				(width 0.1524)
				(type default)
			)
			(layer "F.SilkS")
		)
		(fp_line
			(start 2.1336 1.4224)
			(end 2.1336 -1.4224)
			(stroke
				(width 0.1524)
				(type default)
			)
			(layer "F.SilkS")
		)
		(fp_line
			(start -2.7432 1.4224)
			(end 2.1336 1.4224)
			(stroke
				(width 0.1524)
				(type default)
			)
			(layer "F.SilkS")
		)
		(fp_line
			(start -2.7432 1.4224)
			(end -2.6416 1.4224)
			(stroke
				(width 0.1524)
				(type default)
			)
			(layer "F.SilkS")
		)
		(fp_line
			(start -2.6289 3.4417)
			(end -2.6289 1.4732)
			(stroke
				(width 0.381)
				(type default)
			)
			(layer "F.SilkS")
		)
		(fp_poly
			(pts
				(xy -2.2098 -1.4224) (xy -2.2098 1.4224) (xy 2.2098 1.4224) (xy 2.2098 -1.4224)
			)
			(stroke
				(width 0)
				(type default)
			)
			(fill yes)
			(layer "F.SilkS")
		)
		(fp_rect
			(start -2.450084 2.999994)
			(end 2.450084 -2.999994)
			(stroke
				(width 0)
				(type default)
			)
			(fill no)
			(layer "F.CrtYd")
		)
		(fp_poly
			(pts
				(xy -2.8194 3.6322) (xy -2.8194 -3.6322) (xy 2.8194 -3.6322) (xy 2.8194 1.18364) (xy 2.450084 1.18364)
				(xy 2.450084 -2.999994) (xy -2.450084 -2.999994) (xy -2.450084 2.999994) (xy 2.450084 2.999994)
				(xy 2.450084 1.18618) (xy 2.8194 1.18618) (xy 2.8194 3.6322)
			)
			(stroke
				(width 0)
				(type default)
			)
			(fill no)
			(layer "F.CrtYd")
		)
		(fp_rect
			(start -2.8194 3.6322)
			(end 2.8194 -3.6322)
			(stroke
				(width 0)
				(type default)
			)
			(fill no)
			(layer "F.Fab")
		)
		(pad "1" smd rect
			(at -1.905 2.54 90)
			(size 0.635 1.651)
			(layers "F.Cu" "F.Mask" "F.Paste")
			(net "P12V_A")
		)
		(pad "2" smd rect
			(at -0.635 2.54 90)
			(size 0.635 1.651)
			(layers "F.Cu" "F.Mask" "F.Paste")
			(net "P12V_A")
		)
		(pad "3" smd rect
			(at 0.635 2.54 90)
			(size 0.635 1.651)
			(layers "F.Cu" "F.Mask" "F.Paste")
			(net "P12V_A")
		)
		(pad "4" smd rect
			(at 1.905 2.54 90)
			(size 0.635 1.651)
			(layers "F.Cu" "F.Mask" "F.Paste")
			(net "SW_HDD_N8")
		)
		(pad "5" smd rect
			(at 1.905 -2.54 90)
			(size 0.635 1.651)
			(layers "F.Cu" "F.Mask" "F.Paste")
			(net "P12V_HDD8")
		)
		(pad "6" smd rect
			(at 0.635 -2.54 90)
			(size 0.635 1.651)
			(layers "F.Cu" "F.Mask" "F.Paste")
			(net "P12V_HDD8")
		)
		(pad "7" smd rect
			(at -0.635 -2.54 90)
			(size 0.635 1.651)
			(layers "F.Cu" "F.Mask" "F.Paste")
			(net "P12V_HDD8")
		)
		(pad "8" smd rect
			(at -1.905 -2.54 90)
			(size 0.635 1.651)
			(layers "F.Cu" "F.Mask" "F.Paste")
			(net "P12V_HDD8")
		)
	)
	(footprint ""
		(layer "F.Cu")
		(at 51.980846 -177.778918 -90)
		(property "Reference" "C209"
			(at 0 0 270)
			(layer "F.SilkS")
			(hide yes)
			(effects
				(font
					(size 1.27 1.27)
				)
			)
		)
		(property "Value" "SC1U16V3KX-5GP"
			(at 0 -2.8194 270)
			(unlocked yes)
			(layer "F.Fab")
			(hide yes)
			(effects
				(font
					(size 1.016 1.016)
					(thickness 0.1524)
				)
			)
		)
		(property "Device Type" "C603H36"
			(at 0 -4.3434 270)
			(unlocked yes)
			(layer "F.Fab")
			(hide yes)
			(effects
				(font
					(size 1.016 1.016)
					(thickness 0.1524)
				)
			)
		)
		(duplicate_pad_numbers_are_jumpers no)
		(fp_line
			(start 0.508 0)
			(end -0.508 0)
			(stroke
				(width 0.2032)
				(type default)
			)
			(layer "F.SilkS")
		)
		(fp_rect
			(start -0.5842 1.3335)
			(end 0.5842 -1.3335)
			(stroke
				(width 0)
				(type default)
			)
			(fill no)
			(layer "F.CrtYd")
		)
		(fp_rect
			(start -0.5842 1.3335)
			(end 0.5842 -1.3335)
			(stroke
				(width 0)
				(type default)
			)
			(fill no)
			(layer "F.Fab")
		)
		(pad "1" smd custom
			(at 0 -0.762 270)
			(size 0.2159 0.2159)
			(layers "F.Cu" "F.Mask" "F.Paste")
			(net "P5V_HDD13")
			(options
				(clearance outline)
				(anchor circle)
			)
			(primitives
				(gr_poly
					(pts
						(arc
							(start -0.3302 -0.4318)
							(mid -0.402042 -0.402042)
							(end -0.4318 -0.3302)
						)
						(arc
							(start -0.4318 0.3302)
							(mid -0.402042 0.402042)
							(end -0.3302 0.4318)
						)
						(arc
							(start 0.3302 0.4318)
							(mid 0.402042 0.402042)
							(end 0.4318 0.3302)
						)
						(arc
							(start 0.4318 -0.3302)
							(mid 0.402042 -0.402042)
							(end 0.3302 -0.4318)
						)
					)
					(width 0)
					(fill yes)
				)
			)
		)
		(pad "2" smd custom
			(at 0 0.762 270)
			(size 0.2159 0.2159)
			(layers "F.Cu" "F.Mask" "F.Paste")
			(net "GND")
			(options
				(clearance outline)
				(anchor circle)
			)
			(primitives
				(gr_poly
					(pts
						(arc
							(start -0.3302 -0.4318)
							(mid -0.402042 -0.402042)
							(end -0.4318 -0.3302)
						)
						(arc
							(start -0.4318 0.3302)
							(mid -0.402042 0.402042)
							(end -0.3302 0.4318)
						)
						(arc
							(start 0.3302 0.4318)
							(mid 0.402042 0.402042)
							(end 0.4318 0.3302)
						)
						(arc
							(start 0.4318 -0.3302)
							(mid 0.402042 -0.402042)
							(end 0.3302 -0.4318)
						)
					)
					(width 0)
					(fill yes)
				)
			)
		)
	)
	(footprint ""
		(layer "F.Cu")
		(at 224.1296 -219.295472)
		(property "Reference" "R608"
			(at 0 0 0)
			(layer "F.SilkS")
			(hide yes)
			(effects
				(font
					(size 1.27 1.27)
				)
			)
		)
		(property "Value" "2K2R2F-GP"
			(at 0.064008 -3.993896 0)
			(unlocked yes)
			(layer "F.Fab")
			(hide yes)
			(effects
				(font
					(size 1.016 1.016)
					(thickness 0.1524)
				)
			)
		)
		(property "Device Type" "R402H16"
			(at 0.064008 -5.517896 0)
			(unlocked yes)
			(layer "F.Fab")
			(hide yes)
			(effects
				(font
					(size 1.016 1.016)
					(thickness 0.1524)
				)
			)
		)
		(duplicate_pad_numbers_are_jumpers no)
		(fp_line
			(start -0.508 -0.9398)
			(end -0.508 0.9398)
			(stroke
				(width 0.1524)
				(type default)
			)
			(layer "F.SilkS")
		)
		(fp_line
			(start 0.508 -0.9398)
			(end -0.508 -0.9398)
			(stroke
				(width 0.1524)
				(type default)
			)
			(layer "F.SilkS")
		)
		(fp_rect
			(start -0.508 0.9398)
			(end 0.508 -0.9398)
			(stroke
				(width 0)
				(type default)
			)
			(fill no)
			(layer "F.CrtYd")
		)
		(fp_rect
			(start -0.508 0.9398)
			(end 0.508 -0.9398)
			(stroke
				(width 0)
				(type default)
			)
			(fill no)
			(layer "F.Fab")
		)
		(pad "1" smd custom
			(at 0 -0.4445)
			(size 0.1397 0.1397)
			(layers "F.Cu" "F.Mask" "F.Paste")
			(net "P3V3_STBY_A")
			(options
				(clearance outline)
				(anchor circle)
			)
			(primitives
				(gr_poly
					(pts
						(arc
							(start -0.1778 -0.2794)
							(mid -0.249642 -0.249642)
							(end -0.2794 -0.1778)
						)
						(arc
							(start -0.2794 0.1778)
							(mid -0.249642 0.249642)
							(end -0.1778 0.2794)
						)
						(arc
							(start 0.1778 0.2794)
							(mid 0.249642 0.249642)
							(end 0.2794 0.1778)
						)
						(arc
							(start 0.2794 -0.1778)
							(mid 0.249642 -0.249642)
							(end 0.1778 -0.2794)
						)
					)
					(width 0)
					(fill yes)
				)
			)
		)
		(pad "2" smd custom
			(at 0 0.4445)
			(size 0.1397 0.1397)
			(layers "F.Cu" "F.Mask" "F.Paste")
			(net "I2C_SCC_A_SDA")
			(options
				(clearance outline)
				(anchor circle)
			)
			(primitives
				(gr_poly
					(pts
						(arc
							(start -0.1778 -0.2794)
							(mid -0.249642 -0.249642)
							(end -0.2794 -0.1778)
						)
						(arc
							(start -0.2794 0.1778)
							(mid -0.249642 0.249642)
							(end -0.1778 0.2794)
						)
						(arc
							(start 0.1778 0.2794)
							(mid 0.249642 0.249642)
							(end 0.2794 0.1778)
						)
						(arc
							(start 0.2794 -0.1778)
							(mid 0.249642 -0.249642)
							(end 0.1778 -0.2794)
						)
					)
					(width 0)
					(fill yes)
				)
			)
		)
	)
	(footprint ""
		(layer "F.Cu")
		(at 372.2878 -132.1054)
		(property "Reference" "C556"
			(at 0 0 0)
			(layer "F.SilkS")
			(hide yes)
			(effects
				(font
					(size 1.27 1.27)
				)
			)
		)
		(property "Value" "SCD01U25V2KX-3GP"
			(at 1.1811 -2.7051 0)
			(unlocked yes)
			(layer "F.Fab")
			(hide yes)
			(effects
				(font
					(size 1.016 1.016)
					(thickness 0.1524)
				)
			)
		)
		(property "Device Type" "C402H22"
			(at 1.1811 -4.2291 0)
			(unlocked yes)
			(layer "F.Fab")
			(hide yes)
			(effects
				(font
					(size 1.016 1.016)
					(thickness 0.1524)
				)
			)
		)
		(duplicate_pad_numbers_are_jumpers no)
		(fp_rect
			(start -0.4318 0.9525)
			(end 0.4318 -0.9525)
			(stroke
				(width 0)
				(type default)
			)
			(fill no)
			(layer "F.CrtYd")
		)
		(fp_rect
			(start -0.4318 0.9525)
			(end 0.4318 -0.9525)
			(stroke
				(width 0)
				(type default)
			)
			(fill no)
			(layer "F.Fab")
		)
		(pad "1" smd custom
			(at 0 -0.4445)
			(size 0.1524 0.1524)
			(layers "F.Cu" "F.Mask" "F.Paste")
			(net "MB1_TIME_R")
			(options
				(clearance outline)
				(anchor circle)
			)
			(primitives
				(gr_poly
					(pts
						(arc
							(start 0.3048 -0.2032)
							(mid 0.275042 -0.275042)
							(end 0.2032 -0.3048)
						)
						(arc
							(start -0.2032 -0.3048)
							(mid -0.275042 -0.275042)
							(end -0.3048 -0.2032)
						)
						(arc
							(start -0.3048 0.2032)
							(mid -0.275042 0.275042)
							(end -0.2032 0.3048)
						)
						(arc
							(start 0.2032 0.3048)
							(mid 0.275042 0.275042)
							(end 0.3048 0.2032)
						)
					)
					(width 0)
					(fill yes)
				)
			)
		)
		(pad "2" smd custom
			(at 0 0.4445)
			(size 0.1524 0.1524)
			(layers "F.Cu" "F.Mask" "F.Paste")
			(net "AGND_CURRENT_MONOB")
			(options
				(clearance outline)
				(anchor circle)
			)
			(primitives
				(gr_poly
					(pts
						(arc
							(start 0.3048 -0.2032)
							(mid 0.275042 -0.275042)
							(end 0.2032 -0.3048)
						)
						(arc
							(start -0.2032 -0.3048)
							(mid -0.275042 -0.275042)
							(end -0.3048 -0.2032)
						)
						(arc
							(start -0.3048 0.2032)
							(mid -0.275042 0.275042)
							(end -0.2032 0.3048)
						)
						(arc
							(start 0.2032 0.3048)
							(mid 0.275042 0.275042)
							(end 0.3048 0.2032)
						)
					)
					(width 0)
					(fill yes)
				)
			)
		)
	)
	(footprint ""
		(layer "F.Cu")
		(at 23.732998 -62.270894)
		(property "Reference" "R681"
			(at 0 0 0)
			(layer "F.SilkS")
			(hide yes)
			(effects
				(font
					(size 1.27 1.27)
				)
			)
		)
		(property "Value" "2R6F-GP"
			(at -0.0508 -4.8514 0)
			(unlocked yes)
			(layer "F.Fab")
			(hide yes)
			(effects
				(font
					(size 1.016 1.016)
					(thickness 0.1524)
				)
			)
		)
		(property "Device Type" "R1206H26"
			(at 0 -6.3754 0)
			(unlocked yes)
			(layer "F.Fab")
			(hide yes)
			(effects
				(font
					(size 1.016 1.016)
					(thickness 0.1524)
				)
			)
		)
		(duplicate_pad_numbers_are_jumpers no)
		(fp_line
			(start -1.016 -2.2352)
			(end 1.016 -2.2352)
			(stroke
				(width 0.1524)
				(type default)
			)
			(layer "F.SilkS")
		)
		(fp_line
			(start -1.016 2.2352)
			(end -1.016 -2.2352)
			(stroke
				(width 0.1524)
				(type default)
			)
			(layer "F.SilkS")
		)
		(fp_line
			(start 1.016 -2.2352)
			(end 1.016 2.2352)
			(stroke
				(width 0.1524)
				(type default)
			)
			(layer "F.SilkS")
		)
		(fp_line
			(start 1.016 2.2352)
			(end -1.016 2.2352)
			(stroke
				(width 0.1524)
				(type default)
			)
			(layer "F.SilkS")
		)
		(fp_rect
			(start -1.0922 2.3114)
			(end 1.0922 -2.3114)
			(stroke
				(width 0)
				(type default)
			)
			(fill no)
			(layer "F.CrtYd")
		)
		(fp_poly
			(pts
				(xy -1.0922 -2.3114) (xy 1.0922 -2.3114) (xy 1.0922 2.3114) (xy -1.0922 2.3114)
			)
			(stroke
				(width 0)
				(type default)
			)
			(fill no)
			(layer "F.Fab")
		)
		(pad "1" smd rect
			(at 0 -1.397)
			(size 1.651 1.27)
			(layers "F.Cu" "F.Mask" "F.Paste")
			(net "P5V_HDD24")
		)
		(pad "2" smd rect
			(at 0 1.397)
			(size 1.651 1.27)
			(layers "F.Cu" "F.Mask" "F.Paste")
			(net "5V_PRE_24")
		)
	)
	(footprint ""
		(layer "F.Cu")
		(at 332.105 -45.252894 -90)
		(property "Reference" "Q181"
			(at 0 0 270)
			(layer "F.SilkS")
			(hide yes)
			(effects
				(font
					(size 1.27 1.27)
				)
			)
		)
		(property "Value" "2N7002KDW-GP"
			(at -2.3622 -8.2042 270)
			(unlocked yes)
			(layer "F.Fab")
			(hide yes)
			(effects
				(font
					(size 1.016 1.016)
					(thickness 0.1524)
				)
			)
		)
		(property "Device Type" "SOT-363H44"
			(at -2.3622 -10.1092 270)
			(unlocked yes)
			(layer "F.Fab")
			(hide yes)
			(effects
				(font
					(size 1.016 1.016)
					(thickness 0.1524)
				)
			)
		)
		(duplicate_pad_numbers_are_jumpers no)
		(fp_line
			(start -1.4478 1.7018)
			(end 1.4478 1.7018)
			(stroke
				(width 0.1524)
				(type default)
			)
			(layer "F.SilkS")
		)
		(fp_line
			(start 1.4478 1.7018)
			(end 1.4478 -1.7018)
			(stroke
				(width 0.1524)
				(type default)
			)
			(layer "F.SilkS")
		)
		(fp_line
			(start -1.27 1.524)
			(end -1.27 0.6604)
			(stroke
				(width 0.4826)
				(type default)
			)
			(layer "F.SilkS")
		)
		(fp_line
			(start -1.4478 -1.7018)
			(end -1.4478 1.7018)
			(stroke
				(width 0.1524)
				(type default)
			)
			(layer "F.SilkS")
		)
		(fp_line
			(start 1.4478 -1.7018)
			(end -1.4478 -1.7018)
			(stroke
				(width 0.1524)
				(type default)
			)
			(layer "F.SilkS")
		)
		(fp_poly
			(pts
				(xy -1.524 -1.778) (xy 1.524 -1.778) (xy 1.524 1.778) (xy -1.524 1.778)
			)
			(stroke
				(width 0)
				(type default)
			)
			(fill no)
			(layer "F.CrtYd")
		)
		(fp_poly
			(pts
				(xy -1.524 -1.778) (xy 1.524 -1.778) (xy 1.524 1.778) (xy -1.524 1.778)
			)
			(stroke
				(width 0)
				(type default)
			)
			(fill no)
			(layer "F.Fab")
		)
		(pad "1" smd rect
			(at -0.65024 0.9398 270)
			(size 0.4064 1.016)
			(layers "F.Cu" "F.Mask" "F.Paste")
			(net "GND")
		)
		(pad "2" smd rect
			(at 0 0.9398 270)
			(size 0.4064 1.016)
			(layers "F.Cu" "F.Mask" "F.Paste")
			(net "SW_PWR_R_HDD30")
		)
		(pad "3" smd rect
			(at 0.65024 0.9398 270)
			(size 0.4064 1.016)
			(layers "F.Cu" "F.Mask" "F.Paste")
			(net "SW_HDD_P30")
		)
		(pad "4" smd rect
			(at 0.65024 -0.9398 270)
			(size 0.4064 1.016)
			(layers "F.Cu" "F.Mask" "F.Paste")
			(net "GND")
		)
		(pad "5" smd rect
			(at 0 -0.9398 270)
			(size 0.4064 1.016)
			(layers "F.Cu" "F.Mask" "F.Paste")
			(net "SW_HDD_G30")
		)
		(pad "6" smd rect
			(at -0.65024 -0.9398 270)
			(size 0.4064 1.016)
			(layers "F.Cu" "F.Mask" "F.Paste")
			(net "SW_HDD_R30")
		)
	)
	(footprint ""
		(layer "F.Cu")
		(at 79.924148 -283.152342 -90)
		(property "Reference" "C74"
			(at 0 0 270)
			(layer "F.SilkS")
			(hide yes)
			(effects
				(font
					(size 1.27 1.27)
				)
			)
		)
		(property "Value" "SCD033U25V2KX-GP"
			(at 1.1811 -2.7051 270)
			(unlocked yes)
			(layer "F.Fab")
			(hide yes)
			(effects
				(font
					(size 1.016 1.016)
					(thickness 0.1524)
				)
			)
		)
		(property "Device Type" "C402H22"
			(at 1.1811 -4.2291 270)
			(unlocked yes)
			(layer "F.Fab")
			(hide yes)
			(effects
				(font
					(size 1.016 1.016)
					(thickness 0.1524)
				)
			)
		)
		(duplicate_pad_numbers_are_jumpers no)
		(fp_rect
			(start -0.4318 0.9525)
			(end 0.4318 -0.9525)
			(stroke
				(width 0)
				(type default)
			)
			(fill no)
			(layer "F.CrtYd")
		)
		(fp_rect
			(start -0.4318 0.9525)
			(end 0.4318 -0.9525)
			(stroke
				(width 0)
				(type default)
			)
			(fill no)
			(layer "F.Fab")
		)
		(pad "1" smd custom
			(at 0 -0.4445 270)
			(size 0.1524 0.1524)
			(layers "F.Cu" "F.Mask" "F.Paste")
			(net "SW_HDD_P2")
			(options
				(clearance outline)
				(anchor circle)
			)
			(primitives
				(gr_poly
					(pts
						(arc
							(start 0.3048 -0.2032)
							(mid 0.275042 -0.275042)
							(end 0.2032 -0.3048)
						)
						(arc
							(start -0.2032 -0.3048)
							(mid -0.275042 -0.275042)
							(end -0.3048 -0.2032)
						)
						(arc
							(start -0.3048 0.2032)
							(mid -0.275042 0.275042)
							(end -0.2032 0.3048)
						)
						(arc
							(start 0.2032 0.3048)
							(mid 0.275042 0.275042)
							(end 0.3048 0.2032)
						)
					)
					(width 0)
					(fill yes)
				)
			)
		)
		(pad "2" smd custom
			(at 0 0.4445 270)
			(size 0.1524 0.1524)
			(layers "F.Cu" "F.Mask" "F.Paste")
			(net "GND")
			(options
				(clearance outline)
				(anchor circle)
			)
			(primitives
				(gr_poly
					(pts
						(arc
							(start 0.3048 -0.2032)
							(mid 0.275042 -0.275042)
							(end 0.2032 -0.3048)
						)
						(arc
							(start -0.2032 -0.3048)
							(mid -0.275042 -0.275042)
							(end -0.3048 -0.2032)
						)
						(arc
							(start -0.3048 0.2032)
							(mid -0.275042 0.275042)
							(end -0.2032 0.3048)
						)
						(arc
							(start 0.2032 0.3048)
							(mid 0.275042 0.275042)
							(end 0.3048 0.2032)
						)
					)
					(width 0)
					(fill yes)
				)
			)
		)
	)
)
